 
 
Open CloudServer 
SAS mezzanine I/O specification  
V1.0 
 
Authors: 
Mark Shaw, Director of Hardware Engineering, Microsoft 
Martin Goldstein, Principal Systems Architect, Microsoft 
  


 
2 January 28, 2014 
1 Revision History 
 
Date Name Description 
1/28/2014  Version 1.0 
   
   
   
   
   
   
   
 
 
  



Open Compute Project  Open CloudServer SAS mezzanine I/O specification 
http://opencompute.org 3 
 
© 2014 Microsoft Corporation. 
 
As of January 28, 2014, the following persons or entities have made this Specification available under 
the Open Web Foundation Final Specification Agreement (OWFa 1.0), which is available at 
http://www.openwebfoundation.org/legal/the-owf-1-0-agreements/owfa-1-0 Microsoft Corporation.  
You can review the signed copies of the Open Web Foundation Agreement Version 1.0 for this 
Specification at http://opencompute.org/licensing/, which may also include additional parties to those 
listed above. 
Your use of this Specification may be subject to other third party rights. THIS SPECIFICATION IS 
PROVIDED "AS IS." The contributors expressly disclaim any warranties (express, implied, or otherwise), 
including implied warranties of merchantability, noninfringement, fitness for a particular purpose, or title, 
related to the Specification. The entire risk as to implementing or otherwise using the Specification is 
assumed by the Specification implementer and user. IN NO EVENT WILL ANY PARTY BE LIABLE TO ANY 
OTHER PARTY FOR LOST PROFITS OR ANY FORM OF INDIRECT, SPECIAL, INCIDENTAL, OR 
CONSEQUENTIAL DAMAGES OF ANY CHARACTER FROM ANY CAUSES OF ACTION OF ANY KIND WITH 
RESPECT TO THIS SPECIFICATION OR ITS GOVERNING AGREEMENT, WHETHER BASED ON BREACH OF 
CONTRACT, TORT (INCLUDING NEGLIGENCE), OR OTHERWISE, AND WHETHER OR NOT THE OTHER 
PARTY HAS BEEN ADVISED OF THE POSSIBILITY OF SUCH DAMAGE. 
CONTRIBUTORS AND LICENSORS OF THIS SPECIFICATION MAY HAVE MENTIONED CERTAIN 
TECHNOLOGIES THAT ARE MERELY REFERENCED WITHIN THIS SPECIFICATION AND NOT LICENSED 
UNDER THE OWF CLA OR OWFa. THE FOLLOWING IS A LIST OF MERELY REFERENCED TECHNOLOGY: 
INTELLIGENT PLATFORM MANAGEMENT INTERFACE (IPMI), I2C TRADEMARK OF PHILLIPS 
SEMICONDUCTOR. IMPLEMENTATION OF THESE TECHNOLOGIES MAY BE SUBJECT TO THEIR OWN 
LEGAL TERMS.  



 
4 January 28, 2014 
2 Scope 
This document focuses on the Open CloudServer Storage Attached SCSI (SAS) 
mezzanine card. 
3 Contents 
1 Revision History ......................................................................................................................... 2 
2 Scope ......................................................................................................................................... 4 
3 Contents .................................................................................................................................... 4 
4 Overview.................................................................................................................................... 5 
5 Signaling Interface ..................................................................................................................... 5 
5.1 Connectors ................................................................................................................... 5 
5.2 Signal Definitions .......................................................................................................... 6 
5.3 Connector Pinout ......................................................................................................... 7 
6 Power ........................................................................................................................................ 8 
7 Mechanical ................................................................................................................................ 9 
8 Thermal ................................................................................................................................... 10 
9 Appendix: Commonly Used Acronyms .................................................................................... 12 
 
  



Open Compute Project  Open CloudServer SAS mezzanine I/O specification 
http://opencompute.org 5 
 
4 Overview 
This document outlines specifications for the Open CloudServer Storage Attached 
SCSI (SAS) mezzanine card.  The SAS card interfaces to the processor via PCI-Express 
(PCIe) Gen3 x8 I/O bus and to the motherboard with 8 channels 6 Gigabit SAS.  
Figure 1 shows a block diagram of the connectivity of the SAS mezzanine I/O. 
 
Figure 1. SAS Mezzanine I/O connectivity 
5 Signaling Interface 
The SAS mezzanine interface has been defined to provide high bandwidth and a 
flexible interface. The card receives a PCI-Express Gen3 x8 bus from the CPU. 
5.1 Connectors 
Table 1 shows the connector manufacturer part numbers (MPNs) for the SAS 
mezzanine cards. 
Table 1. Connector Part Numbers, SAS Mezzanine Card 
Manufacturer Card connector MPN Motherboard connector MPN 
Samtec SEAM-20-03.5-S-08-2-A-K-TR SEAF-20-06.5-S-08-2-A-K-TR 


 
6 January 28, 2014 
Manufacturer Card connector MPN Motherboard connector MPN 
Molex 45970-2385 45971-2385 
The stackup height of the SEAM is 10mm with a 6.5mm SEAF and a 3.5mm SEAM 
connector. In this configuration, it is expected that taller components are placed on 
the top side of the printed circuit board (PCB), as shown in Figure 2. 
SEAF6.5mm
3.5mm
10mm
Device
Heatsink
Backside Keepout
SEAM
 
Figure 2. Connector stackup 
5.2 Signal Definitions 
Table 2 defines the signals used in the NIC mezzanine interface. 
Table 2. NIC Mezzanine Connector Signal Definitions 
Bus type IO Logic Definition 
P3E_CPU1_SAS_RX_DP/N[7:0] O CML PCIe Gen3 from the SAS Mezz to the CPU 
P3E_CPU1_SAS_TX_DP/N[7:0] I CML PCIe Gen3 from the CPU to the SAS Mezz 
CLK_100M_NIC_PE_DP/N I CML 100MHz PCIe clock 
PCIE_RESET_N I 3.3V PCIe  reset 
MEZZ_PRESENT_N O 3.3V Mezz present –  should be GND on Mezzanine 
SAS_TD_CH[7:0]P/N O CML SAS transmit from Mezz to motherboard 



Open Compute Project  Open CloudServer SAS mezzanine I/O specification 
http://opencompute.org 7 
 
Bus type IO Logic Definition 
SAS_RD_CH[3:0]P/N I CML SAS receive from motherboard to Mezz 
SMB_ALERT_N O 3.3V 
I2C alert from SAS Mezz to baseboard 
management controller (BMC) 
SMB_SCL I 3.3V I2C to BMC 
SMB_SDA I/O 3.3V I2C to BMC 
SAS_MEZZ_ID[2:0] O 3.3V NIC Mezz ID –  connected to BMC on motherboard 
P3V3 I 3.3V 3.3V input power 
P3V3_AUX I 3.3V 3.3V aux input power 
P12V_AUX I 12V 12V input power 
Ground   Ground pins 
5.3 Connector Pinout 
Table 3 shows the SAS mezzanine connector interfaces and pinout numbers. 
Table 3. SAS Mezzanine Connector Interface 
1 
MEZZ_PR
SNT_N 
GND 
IRQ_LVC3_WA
KE_N 
GND 
RST_PE
RST0_N 
GND 
FM_SMB
_ALERT_
N 
GND 8 
9 GND 
P3e_Cpu1_Me
zz_Tx_Dp<7> 
GND 
P3e_Cpu1_ME
ZZ_Rx_Dp<7> 
GND 
SAS_TD_C
H1N 
GND 
SAS_RD_C
H1N 
16 
17 GND 
P3e_Cpu1_Me
zz_Tx_Dn<7> 
GND 
P3e_Cpu1_ME
ZZ_Rx_Dn<7> 
GND 
SAS_TD_C
H1P 
GND 
SAS_RD_C
H1P 
24 
25 
P3e_Cpu1
_Mezz_Tx
_Dp<6> 
GND 
P3e_Cpu1_ME
ZZ_Rx_Dp<6> 
GND 
SAS_TD
_CH2N 
GND 
SAS_RD_
CH2N 
GND 32 
33 
P3e_Cpu1
_Mezz_Tx
_Dn<6> 
GND 
P3e_Cpu1_ME
ZZ_Rx_Dn<6> 
GND 
SAS_TD
_CH2P 
GND 
SAS_RD_
CH2P 
GND 40 
41 GND 
P3e_Cpu1_Me
zz_Tx_Dp<5> 
GND 
P3e_Cpu1_ME
ZZ_Rx_Dp<5> 
GND 
SAS_TD_C
H3N 
GND 
SAS_RD_C
H3N 
48 
49 GND 
P3e_Cpu1_Me
zz_Tx_Dn<5> 
GND 
P3e_Cpu1_ME
ZZ_Rx_Dn<5> 
GND 
SAS_TD_C
H3P 
GND 
SAS_RD_C
H3P 
56 



 
8 January 28, 2014 
57 
P3e_Cpu1
_Mezz_Tx
_Dp<4> 
GND 
P3e_Cpu1_ME
ZZ_Rx_Dp<4> 
GND 
SAS_TD
_CH4N 
GND 
SAS_RD_
CH4N 
GND 64 
65 
P3e_Cpu1
_Mezz_Tx
_Dn<4> 
GND 
P3e_Cpu1_ME
ZZ_Rx_Dn<4> 
GND 
SAS_TD
_CH4P 
GND 
SAS_RD_
CH4P 
GND 72 
73 GND 
P3e_Cpu1_Me
zz_Tx_Dp<3> 
GND 
P3e_Cpu1_ME
ZZ_Rx_Dp<3> 
GND 
SAS_TD_C
H5N 
GND 
SAS_RD_C
H5N 
80 
81 GND 
P3e_Cpu1_Me
zz_Tx_Dn<3> 
GND 
P3e_Cpu1_ME
ZZ_Rx_Dn<3> 
GND 
SAS_TD_C
H5P 
GND 
SAS_RD_C
H5P 
88 
89 
P3e_Cpu1
_Mezz_Tx
_Dp<2> 
GND 
P3e_Cpu1_ME
ZZ_Rx_Dp<2> 
GND 
SAS_TD
_CH6N 
GND 
SAS_RD_
CH6N 
GND 96 
97 
P3e_Cpu1
_Mezz_Tx
_Dn<2> 
GND 
P3e_Cpu1_ME
ZZ_Rx_Dn<2> 
GND 
SAS_TD
_CH6P 
GND 
SAS_RD_
CH6P 
GND 104 
105 GND 
P3e_Cpu1_Me
zz_Tx_Dp<1> 
GND 
P3e_Cpu1_ME
ZZ_Rx_Dp<1> 
GND 
SAS_TD_C
H7N 
GND 
SAS_RD_C
H7N 
112 
113 GND 
P3e_Cpu1_Me
zz_Tx_Dn<1> 
GND 
P3e_Cpu1_ME
ZZ_Rx_Dn<1> 
GND 
SAS_TD_C
H7P 
GND 
SAS_RD_C
H7P 
120 
121 
P3e_Cpu1
_Mezz_Tx
_Dp<0> 
GND 
P3e_Cpu1_ME
ZZ_Rx_Dp<0> 
GND 
SAS_TD
_CH8N 
GND 
SAS_RD_
CH8N 
GND 128 
129 
P3e_Cpu1
_Mezz_Tx
_Dn<0> 
GND 
P3e_Cpu1_ME
ZZ_Rx_Dn<0> 
GND 
SAS_TD
_CH8P 
GND 
SAS_RD_
CH8P 
GND 136 
137 GND Spare GND 
SAS_MEZZ_ID
0 
GND 
CLK_100M
_MEZZ_DP 
GND 
SMB_MEZZ
_3V3STBY_
CLK 
144 
145 
P12V_ME
ZZ 
P3V3_AUX P3V3 Spare GND 
CLK_100M
_MEZZ_D
N 
GND 
SMB_MEZZ
_3V3STBY_
DATA 
152 
153 
P12V_ME
ZZ 
P3V3_AUX P3V3 P3V3 
SAS_M
EZZ_ID
1 
GND 
SAS_MEZ
Z_ID2 
GND 160 
 
6 Power 
Table 4 shows the SAS mezzanine power ratings for the rail. 
 



Open Compute Project  Open CloudServer SAS mezzanine I/O specification 
http://opencompute.org 9 
 
Table 4. LAN Mezzanine Power Ratings 
Power rails Amps/pin (at 40oC) Total number of 
pins Budget (W) 
12V_Mezz 2 2 43.2W 
3.3V_AUX 2 2 11.88W 
3.3V 2 3 17.82W 
Total power budget per mezzanine card) 25W 
Figure 3. SAS mezzanine power-up sequence shows the SAS mezzanine power-up 
sequence.  
 
Figure 3. SAS mezzanine power-up sequence 
Note that the maximum power consumption of the mezzanine cards is 25W. The 
reset signal conforms to the PCI Express reset specifications. 
7 Mechanical 
The storage controller mezzanine interface has been defined to enable an 8-channel, 
6G or a 12G SAS I/O controller. The card receives a PCI-Express x8 bus from the 
chipset. Note that the current version of the tray only supports 6G signaling rates.  
Figure 4 shows the SAS mezzanine dimensions. Note that PCB thickness can vary as 


 
10 January 28, 2014 
long as the keep-in volumes are not violated.  
 
  
Figure 4. SAS mezzanine dimensions 
8 Thermal  
The SAS mezzanine cards are designed to be located at the extreme downstream 
position of the server, so the air is heated by all of the upstream components before 
reaching the cards. The direction of air flow is shown in Figure 4.   



Open Compute Project  Open CloudServer SAS mezzanine I/O specification 
http://opencompute.org 11 
 
Table 5 shows the worst-case environmental conditions that can be expected at the 
SAS mezzanine card inlet. The thermal solution and component selection should be 
sufficient for these conditions.  
Table 5. Environmental Operating Conditions, SAS Mezzanine Card 
Variable Worst case operating condition 
Approaching airflow rate 200 ft/min, uniform 
Maximum allowable pressure drop across card 0.040 “H2O max at 200 ft/min 
Approaching airflow temperature 68OC, uniform 
  



 
12 January 28, 2014 
9 Appendix: Commonly Used Acronyms 
This section provides definitions of acronyms used in the system specifications. 
ACPI – advanced configuration and 
power interface  
AHCI – advanced host controller 
interface 
AHJ – authority having jurisdiction 
ANSI – American National 
Standards Institute 
API – application programming 
interface 
ASHRAE – American Society of 
Heating, Refrigerating and Air 
Conditioning Engineers 
ASIC – application-specific 
integrated circuit 
BCD – binary-coded decimal 
BIOS – basic input/output system 
BMC – baseboard management 
controller 
CFM – cubic feet per minute 
(measure of volume flow rate) 
CM – Chassis Manager 
CMOS – complementary metal–
oxide–semiconductor 
COLO – co-location 
CTS – clear to send 
DCMI – Data Center Manageability 
Interface 
DDR3 – double data rate type 3  
DHCP – dynamic host 
configuration protocol 
DIMM – dual inline memory 
module  
DPC – DIMMs per memory channel  
DRAM – dynamic random access 
memory 
DSR – data set ready 
DTR – data terminal ready 
ECC – error-correcting code 
EEPROM - electrically erasable 
programmable read-only memory 
EIA – Electronic Industries Alliance 
EMC – electromagnetic 
compatibility 
EMI – electromagnetic interference 
FRU – field replaceable unit 
FTP – file transfer protocol 
GPIO – general purpose input 
output 
GUID – globally unique identifier 
HBI – high business intelligence 
HCK – Windows Hardware 
Certification Kit 
HMD – hardware monitoring 
device 
HT – hyperthreading 
I2C – inter-integrated circuit 
IBC – international building code 
IDE – integrated development 
environment 



Open Compute Project  Open CloudServer SAS mezzanine I/O specification 
http://opencompute.org 13 
 
IEC – International Electrotechnical 
Commission 
IOC – I/O controller 
IPMI – intelligent platform 
management interface 
IPsec – IP security 
ITPAC – IT pre-assembled 
components 
JBOD – “just a bunch of disks” 
KCS – keyboard controller style 
L2 – layer 2 
LAN – local area network 
LFF – large form factor 
LPC – low pin count 
LS – least significant 
LUN – logical unit number 
MAC – media access control 
MDC – modular data center 
containers 
MLC – multi-level call 
MTBF – mean time between 
failures  
MUX - multiplexer 
NIC – network interface card 
NUMA – non-uniform memory 
access 
OOB – out of band 
OSHA - Occupational Safety & 
Health Administration 
OTS – off the shelf 
PCB – printed circuit board 
PCIe – peripheral component 
interconnect express 
PCH – platform control hub 
PDB – power distribution 
backplane 
PDU – power distribution unit 
Ph-ph – phase to phase 
Ph-N – phase to neutral 
PNP – plug and play 
POST – power-on self-test 
PSU – power supply unit 
PWM – pulse-width modulation 
PXE – preboot execution 
environment 
QDR – quad data rate 
QFN – quad flat package no-lead 
QPI – Intel QuickPath Interconnect 
QSFP – Quad small form-factor 
pluggable 
RAID – redundant array of 
independent disks 
REST - representational state 
transfer 
RM – Rack Manager 
RMA – remote management agent 
ROC – RAID-on-chip controller 
RSS – receive-side scaling 
RTS – request to send 
RU – rack unit 
RxD – received data 
SAS – serial-attached small 
computer system interface (SCSI) 



 
14 January 28, 2014 
SATA – serial AT attachment 
SCK – serial clock 
SCSI – small computer system 
interface 
SDA – serial data signal 
SDR – sensor data record 
SFF – small form factor 
SFP - small form-factor pluggable  
SMBUS – systems management 
bus 
SMBIOS – systems management 
BIOS 
SOL – serial over LAN 
SPI – serial peripheral interface 
SSD – solid-state drive 
TB – tray backplane 
TDP – thermal design power 
TB – tray backplane 
TOR – top of rack 
TPM – trusted platform module 
TxD – transmit data 
U – rack unit 
UART – universal asynchronous 
receiver/transmitter 
UEFI – unified extensible firmware 
interface 
UL – Underwriters Laboratories 
UPS – uninterrupted power supply 
Vpp – voltage peak to peak 
WMI – Windows Management 
Interface 
 